(kicad_pcb
	(version 20241229)
	(generator "pcbnew")
	(generator_version "9.0")
	(general
		(thickness 1.711)
		(legacy_teardrops no)
	)
	(paper "A4")
	(title_block
		(title "Antmicro Baseboard for Jetson AGX Thor")
		(date "2026-02-18")
		(rev "1.1.0")
		(company "Antmicro Ltd")
		(comment 1 "www.antmicro.com")
		(comment 9 "footprints 985-989 of 1170")
	)
	(layers
		(0 "F.Cu" signal)
		(4 "In1.Cu" signal)
		(6 "In2.Cu" signal)
		(8 "In3.Cu" signal)
		(10 "In4.Cu" jumper)
		(12 "In5.Cu" signal)
		(14 "In6.Cu" signal)
		(16 "In7.Cu" signal)
		(18 "In8.Cu" signal)
		(2 "B.Cu" signal)
		(9 "F.Adhes" user "F.Adhesive")
		(11 "B.Adhes" user "B.Adhesive")
		(13 "F.Paste" user)
		(15 "B.Paste" user)
		(5 "F.SilkS" user "F.Silkscreen")
		(7 "B.SilkS" user "B.Silkscreen")
		(1 "F.Mask" user)
		(3 "B.Mask" user)
		(17 "Dwgs.User" user "User.Drawings")
		(19 "Cmts.User" user "User.Comments")
		(21 "Eco1.User" user "User.Eco1")
		(23 "Eco2.User" user "User.Eco2")
		(25 "Edge.Cuts" user)
		(27 "Margin" user)
		(31 "F.CrtYd" user "F.Courtyard")
		(29 "B.CrtYd" user "B.Courtyard")
		(35 "F.Fab" user)
		(33 "B.Fab" user)
	)
	(footprint "antmicro-footprints:C_0402_1005Metric"
		(layer "B.Cu")
		(at 111.81 70.62 180)
		(descr "Capacitor SMD 0402")
		(tags "capacitor SMD 0402")
		(property "Reference" "C18"
			(at -1.39 -1.48 0)
			(layer "B.SilkS")
			(effects
				(font
					(size 0.7 0.7)
					(thickness 0.15)
				)
				(justify left bottom mirror)
			)
		)
		(property "Value" "C_100n_0402"
			(at -1.022927 -2.155213 0)
			(layer "B.Fab")
			(effects
				(font
					(size 0.7 0.7)
					(thickness 0.15)
				)
				(justify left bottom mirror)
			)
		)
		(property "Datasheet" "https://www.murata.com/products/productdetail?partno=GRM155R61H104KE14%23"
			(at 0 0 0)
			(layer "B.Fab")
			(hide yes)
			(effects
				(font
					(size 1.27 1.27)
					(thickness 0.15)
				)
				(justify mirror)
			)
		)
		(property "Description" "SMD Multilayer Ceramic Capacitor, 0.1 µF, 50 V, 0402 [1005 Metric], ± 10%, X5R, GRM Series"
			(at 0 0 0)
			(layer "B.Fab")
			(hide yes)
			(effects
				(font
					(size 1.27 1.27)
					(thickness 0.15)
				)
				(justify mirror)
			)
		)
		(property "MPN" "GRM155R61H104KE14D"
			(at 0 0 0)
			(unlocked yes)
			(layer "B.Fab")
			(hide yes)
			(effects
				(font
					(size 1 1)
					(thickness 0.15)
				)
				(justify mirror)
			)
		)
		(property "Val" "100n"
			(at 0 0 0)
			(unlocked yes)
			(layer "B.Fab")
			(hide yes)
			(effects
				(font
					(size 1 1)
					(thickness 0.15)
				)
				(justify mirror)
			)
		)
		(property "Voltage" "50V"
			(at 0 0 0)
			(unlocked yes)
			(layer "B.Fab")
			(hide yes)
			(effects
				(font
					(size 1 1)
					(thickness 0.15)
				)
				(justify mirror)
			)
		)
		(property "Dielectric" "X5R"
			(at 0 0 0)
			(unlocked yes)
			(layer "B.Fab")
			(hide yes)
			(effects
				(font
					(size 1 1)
					(thickness 0.15)
				)
				(justify mirror)
			)
		)
		(property "Manufacturer" "Murata"
			(at 0 0 0)
			(unlocked yes)
			(layer "B.Fab")
			(hide yes)
			(effects
				(font
					(size 1 1)
					(thickness 0.15)
				)
				(justify mirror)
			)
		)
		(property "License" "Apache-2.0"
			(at 0 0 0)
			(unlocked yes)
			(layer "B.Fab")
			(hide yes)
			(effects
				(font
					(size 1 1)
					(thickness 0.15)
				)
				(justify mirror)
			)
		)
		(property "Author" "Antmicro"
			(at 0 0 0)
			(unlocked yes)
			(layer "B.Fab")
			(hide yes)
			(effects
				(font
					(size 1 1)
					(thickness 0.15)
				)
				(justify mirror)
			)
		)
		(sheetname "/SoM_Power/")
		(sheetfile "som_power.kicad_sch")
		(attr smd)
		(fp_rect
			(start -0.925 0.47)
			(end 0.925 -0.47)
			(stroke
				(width 0.05)
				(type default)
			)
			(fill no)
			(layer "B.CrtYd")
		)
		(fp_line
			(start 0.504 0.25)
			(end 0.504 -0.248)
			(stroke
				(width 0.15)
				(type solid)
			)
			(layer "B.Fab")
		)
		(fp_line
			(start 0.504 -0.248)
			(end -0.494 -0.248)
			(stroke
				(width 0.15)
				(type solid)
			)
			(layer "B.Fab")
		)
		(fp_line
			(start -0.494 0.25)
			(end 0.504 0.25)
			(stroke
				(width 0.15)
				(type solid)
			)
			(layer "B.Fab")
		)
		(fp_line
			(start -0.494 -0.248)
			(end -0.494 0.25)
			(stroke
				(width 0.15)
				(type solid)
			)
			(layer "B.Fab")
		)
		(fp_text user "${REFERENCE}"
			(at -0.939 -4.599 0)
			(layer "B.Fab")
			(effects
				(font
					(size 0.7 0.7)
					(thickness 0.15)
				)
				(justify left bottom mirror)
			)
		)
		(fp_text user "Author: Antmicro"
			(at -0.939 -3.399 0)
			(layer "B.Fab")
			(effects
				(font
					(size 0.7 0.7)
					(thickness 0.15)
				)
				(justify left bottom mirror)
			)
		)
		(fp_text user "License: Apache-2.0"
			(at -0.939 -5.799 0)
			(layer "B.Fab")
			(effects
				(font
					(size 0.7 0.7)
					(thickness 0.15)
				)
				(justify left bottom mirror)
			)
		)
		(pad "1" smd roundrect
			(at -0.48 0 180)
			(size 0.59 0.64)
			(layers "B.Cu" "B.Mask" "B.Paste")
			(roundrect_rratio 0.25)
			(net 1 "GND")
			(pintype "passive")
		)
		(pad "2" smd roundrect
			(at 0.48 0 180)
			(size 0.59 0.64)
			(layers "B.Cu" "B.Mask" "B.Paste")
			(roundrect_rratio 0.25)
			(net 213 "+5V_SOM")
			(pintype "passive")
		)
	)
	(footprint "antmicro-footprints:C_0402_1005Metric"
		(layer "B.Cu")
		(at 119.7 151.2 180)
		(descr "Capacitor SMD 0402")
		(tags "capacitor SMD 0402")
		(property "Reference" "C209"
			(at -3.7035 -0.33 0)
			(layer "B.SilkS")
			(effects
				(font
					(size 0.7 0.7)
					(thickness 0.15)
				)
				(justify left bottom mirror)
			)
		)
		(property "Value" "C_100n_0402"
			(at -1.022927 -2.155213 0)
			(layer "B.Fab")
			(effects
				(font
					(size 0.7 0.7)
					(thickness 0.15)
				)
				(justify left bottom mirror)
			)
		)
		(property "Datasheet" "https://www.murata.com/products/productdetail?partno=GRM155R61H104KE14%23"
			(at 0 0 0)
			(layer "B.Fab")
			(hide yes)
			(effects
				(font
					(size 1.27 1.27)
					(thickness 0.15)
				)
				(justify mirror)
			)
		)
		(property "Description" "SMD Multilayer Ceramic Capacitor, 0.1 µF, 50 V, 0402 [1005 Metric], ± 10%, X5R, GRM Series"
			(at 0 0 0)
			(layer "B.Fab")
			(hide yes)
			(effects
				(font
					(size 1.27 1.27)
					(thickness 0.15)
				)
				(justify mirror)
			)
		)
		(property "MPN" "GRM155R61H104KE14D"
			(at 0 0 0)
			(unlocked yes)
			(layer "B.Fab")
			(hide yes)
			(effects
				(font
					(size 1 1)
					(thickness 0.15)
				)
				(justify mirror)
			)
		)
		(property "Manufacturer" "Murata"
			(at 0 0 0)
			(unlocked yes)
			(layer "B.Fab")
			(hide yes)
			(effects
				(font
					(size 1 1)
					(thickness 0.15)
				)
				(justify mirror)
			)
		)
		(property "License" "Apache-2.0"
			(at 0 0 0)
			(unlocked yes)
			(layer "B.Fab")
			(hide yes)
			(effects
				(font
					(size 1 1)
					(thickness 0.15)
				)
				(justify mirror)
			)
		)
		(property "Author" "Antmicro"
			(at 0 0 0)
			(unlocked yes)
			(layer "B.Fab")
			(hide yes)
			(effects
				(font
					(size 1 1)
					(thickness 0.15)
				)
				(justify mirror)
			)
		)
		(property "Val" "100n"
			(at 0 0 0)
			(unlocked yes)
			(layer "B.Fab")
			(hide yes)
			(effects
				(font
					(size 1 1)
					(thickness 0.15)
				)
				(justify mirror)
			)
		)
		(property "Voltage" "50V"
			(at 0 0 0)
			(unlocked yes)
			(layer "B.Fab")
			(hide yes)
			(effects
				(font
					(size 1 1)
					(thickness 0.15)
				)
				(justify mirror)
			)
		)
		(property "Dielectric" "X5R"
			(at 0 0 0)
			(unlocked yes)
			(layer "B.Fab")
			(hide yes)
			(effects
				(font
					(size 1 1)
					(thickness 0.15)
				)
				(justify mirror)
			)
		)
		(sheetname "/Peripherals/")
		(sheetfile "peripherals.kicad_sch")
		(attr smd)
		(fp_poly
			(pts
				(xy -0.925 0.47) (xy 0.925 0.47) (xy 0.925 -0.47) (xy -0.925 -0.47)
			)
			(stroke
				(width 0.05)
				(type default)
			)
			(fill no)
			(layer "B.CrtYd")
		)
		(fp_line
			(start 0.504 0.25)
			(end 0.504 -0.248)
			(stroke
				(width 0.15)
				(type solid)
			)
			(layer "B.Fab")
		)
		(fp_line
			(start 0.504 -0.248)
			(end -0.494 -0.248)
			(stroke
				(width 0.15)
				(type solid)
			)
			(layer "B.Fab")
		)
		(fp_line
			(start -0.494 0.25)
			(end 0.504 0.25)
			(stroke
				(width 0.15)
				(type solid)
			)
			(layer "B.Fab")
		)
		(fp_line
			(start -0.494 -0.248)
			(end -0.494 0.25)
			(stroke
				(width 0.15)
				(type solid)
			)
			(layer "B.Fab")
		)
		(fp_text user "${REFERENCE}"
			(at -0.939 -4.599 0)
			(layer "B.Fab")
			(effects
				(font
					(size 0.7 0.7)
					(thickness 0.15)
				)
				(justify left bottom mirror)
			)
		)
		(fp_text user "Author: Antmicro"
			(at -0.939 -3.399 0)
			(layer "B.Fab")
			(effects
				(font
					(size 0.7 0.7)
					(thickness 0.15)
				)
				(justify left bottom mirror)
			)
		)
		(fp_text user "License: Apache-2.0"
			(at -0.939 -5.799 0)
			(layer "B.Fab")
			(effects
				(font
					(size 0.7 0.7)
					(thickness 0.15)
				)
				(justify left bottom mirror)
			)
		)
		(pad "1" smd roundrect
			(at -0.48 0 180)
			(size 0.59 0.64)
			(layers "B.Cu" "B.Mask" "B.Paste")
			(roundrect_rratio 0.25)
			(net 1 "GND")
			(pintype "passive")
		)
		(pad "2" smd roundrect
			(at 0.48 0 180)
			(size 0.59 0.64)
			(layers "B.Cu" "B.Mask" "B.Paste")
			(roundrect_rratio 0.25)
			(net 4 "+3V3_AON")
			(pintype "passive")
		)
	)
	(footprint "antmicro-footprints:R_0402_1005Metric"
		(layer "B.Cu")
		(at 179.75 57.5 -90)
		(descr "Resistor SMD 0402")
		(tags "resistor SMD 0402")
		(property "Reference" "R51"
			(at -3.48 -0.365532 90)
			(layer "B.SilkS")
			(effects
				(font
					(size 0.7 0.7)
					(thickness 0.15)
				)
				(justify left bottom mirror)
			)
		)
		(property "Value" "R_2k2_0402"
			(at -1.011843 -1.772047 90)
			(layer "B.Fab")
			(effects
				(font
					(size 0.7 0.7)
					(thickness 0.15)
				)
				(justify left bottom mirror)
			)
		)
		(property "Datasheet" "https://www.bourns.com/docs/product-datasheets/cr.pdf"
			(at 0 0 90)
			(layer "B.Fab")
			(hide yes)
			(effects
				(font
					(size 1.27 1.27)
					(thickness 0.15)
				)
				(justify mirror)
			)
		)
		(property "Description" "SMD Chip Resistor, 2.2 kohm, ± 1%, 62.5 mW, 0402 [1005 Metric], Thick Film, General Purpose"
			(at 0 0 90)
			(layer "B.Fab")
			(hide yes)
			(effects
				(font
					(size 1.27 1.27)
					(thickness 0.15)
				)
				(justify mirror)
			)
		)
		(property "MPN" "CR0402-FX-2201GLF"
			(at 0 0 90)
			(unlocked yes)
			(layer "B.Fab")
			(hide yes)
			(effects
				(font
					(size 1 1)
					(thickness 0.15)
				)
				(justify mirror)
			)
		)
		(property "Manufacturer" "Bourns"
			(at 0 0 90)
			(unlocked yes)
			(layer "B.Fab")
			(hide yes)
			(effects
				(font
					(size 1 1)
					(thickness 0.15)
				)
				(justify mirror)
			)
		)
		(property "License" "Apache-2.0"
			(at 0 0 90)
			(unlocked yes)
			(layer "B.Fab")
			(hide yes)
			(effects
				(font
					(size 1 1)
					(thickness 0.15)
				)
				(justify mirror)
			)
		)
		(property "Author" "Antmicro"
			(at 0 0 90)
			(unlocked yes)
			(layer "B.Fab")
			(hide yes)
			(effects
				(font
					(size 1 1)
					(thickness 0.15)
				)
				(justify mirror)
			)
		)
		(property "Val" "2k2"
			(at 0 0 90)
			(unlocked yes)
			(layer "B.Fab")
			(hide yes)
			(effects
				(font
					(size 1 1)
					(thickness 0.15)
				)
				(justify mirror)
			)
		)
		(property "Tolerance" "1%"
			(at 0 0 90)
			(unlocked yes)
			(layer "B.Fab")
			(hide yes)
			(effects
				(font
					(size 1 1)
					(thickness 0.15)
				)
				(justify mirror)
			)
		)
		(sheetname "/Power/")
		(sheetfile "power.kicad_sch")
		(attr smd)
		(fp_rect
			(start -0.925 0.47)
			(end 0.925 -0.47)
			(stroke
				(width 0.05)
				(type default)
			)
			(fill no)
			(layer "B.CrtYd")
		)
		(fp_rect
			(start -0.5 0.25)
			(end 0.5 -0.25)
			(stroke
				(width 0.15)
				(type solid)
			)
			(fill no)
			(layer "B.Fab")
		)
		(fp_text user "License: Apache-2.0"
			(at -0.95 -5.169 90)
			(layer "B.Fab")
			(effects
				(font
					(size 0.7 0.7)
					(thickness 0.15)
				)
				(justify left bottom mirror)
			)
		)
		(fp_text user "Author: Antmicro"
			(at -0.95 -4.169 90)
			(layer "B.Fab")
			(effects
				(font
					(size 0.7 0.7)
					(thickness 0.15)
				)
				(justify left bottom mirror)
			)
		)
		(fp_text user "${REFERENCE}"
			(at -0.95 -3.168 90)
			(layer "B.Fab")
			(effects
				(font
					(size 0.7 0.7)
					(thickness 0.15)
				)
				(justify left bottom mirror)
			)
		)
		(pad "1" smd roundrect
			(at -0.48 0 270)
			(size 0.59 0.64)
			(layers "B.Cu" "B.Mask" "B.Paste")
			(roundrect_rratio 0.25)
			(net 529 "Net-(D10-A)")
			(pintype "passive")
		)
		(pad "2" smd roundrect
			(at 0.48 0 270)
			(size 0.59 0.64)
			(layers "B.Cu" "B.Mask" "B.Paste")
			(roundrect_rratio 0.25)
			(net 12 "SYS_VIN_HV")
			(pintype "passive")
		)
	)
	(footprint "antmicro-footprints:R_0402_1005Metric"
		(layer "B.Cu")
		(at 219.4 95.4)
		(descr "Resistor SMD 0402")
		(tags "resistor SMD 0402")
		(property "Reference" "R273"
			(at -1.5 -2.5 0)
			(layer "B.SilkS")
			(effects
				(font
					(size 0.7 0.7)
					(thickness 0.15)
				)
				(justify right top mirror)
			)
		)
		(property "Value" "R_10k_0402"
			(at -1.011843 -1.772047 0)
			(layer "B.Fab")
			(effects
				(font
					(size 0.7 0.7)
					(thickness 0.15)
				)
				(justify right top mirror)
			)
		)
		(property "Datasheet" "https://www.bourns.com/docs/product-datasheets/cr.pdf"
			(at 0 0 0)
			(layer "B.Fab")
			(hide yes)
			(effects
				(font
					(size 1.27 1.27)
					(thickness 0.15)
				)
				(justify mirror)
			)
		)
		(property "Description" "SMD Chip Resistor, 10 kohm, ± 1%, 62.5 mW, 0402 [1005 Metric], Thick Film, General Purpose"
			(at 0 0 0)
			(layer "B.Fab")
			(hide yes)
			(effects
				(font
					(size 1.27 1.27)
					(thickness 0.15)
				)
				(justify mirror)
			)
		)
		(property "MPN" "CR0402-FX-1002GLF"
			(at 0 0 180)
			(unlocked yes)
			(layer "B.Fab")
			(hide yes)
			(effects
				(font
					(size 1 1)
					(thickness 0.15)
				)
				(justify mirror)
			)
		)
		(property "Manufacturer" "Bourns"
			(at 0 0 180)
			(unlocked yes)
			(layer "B.Fab")
			(hide yes)
			(effects
				(font
					(size 1 1)
					(thickness 0.15)
				)
				(justify mirror)
			)
		)
		(property "License" "Apache-2.0"
			(at 0 0 180)
			(unlocked yes)
			(layer "B.Fab")
			(hide yes)
			(effects
				(font
					(size 1 1)
					(thickness 0.15)
				)
				(justify mirror)
			)
		)
		(property "Author" "Antmicro"
			(at 0 0 180)
			(unlocked yes)
			(layer "B.Fab")
			(hide yes)
			(effects
				(font
					(size 1 1)
					(thickness 0.15)
				)
				(justify mirror)
			)
		)
		(property "Val" "10k"
			(at 0 0 180)
			(unlocked yes)
			(layer "B.Fab")
			(hide yes)
			(effects
				(font
					(size 1 1)
					(thickness 0.15)
				)
				(justify mirror)
			)
		)
		(property "Tolerance" "1%"
			(at 0 0 180)
			(unlocked yes)
			(layer "B.Fab")
			(hide yes)
			(effects
				(font
					(size 1 1)
					(thickness 0.15)
				)
				(justify mirror)
			)
		)
		(sheetname "/USB DP Alt mode/")
		(sheetfile "usb_dp.kicad_sch")
		(attr smd)
		(fp_rect
			(start -0.925 0.47)
			(end 0.925 -0.47)
			(stroke
				(width 0.05)
				(type default)
			)
			(fill no)
			(layer "B.CrtYd")
		)
		(fp_rect
			(start -0.5 0.25)
			(end 0.5 -0.25)
			(stroke
				(width 0.15)
				(type solid)
			)
			(fill no)
			(layer "B.Fab")
		)
		(fp_text user "${REFERENCE}"
			(at -0.95 -3.168 0)
			(layer "B.Fab")
			(effects
				(font
					(size 0.7 0.7)
					(thickness 0.15)
				)
				(justify right top mirror)
			)
		)
		(fp_text user "License: Apache-2.0"
			(at -0.95 -5.169 0)
			(layer "B.Fab")
			(effects
				(font
					(size 0.7 0.7)
					(thickness 0.15)
				)
				(justify right top mirror)
			)
		)
		(fp_text user "Author: Antmicro"
			(at -0.95 -4.169 0)
			(layer "B.Fab")
			(effects
				(font
					(size 0.7 0.7)
					(thickness 0.15)
				)
				(justify right top mirror)
			)
		)
		(pad "1" smd roundrect
			(at -0.48 0)
			(size 0.59 0.64)
			(layers "B.Cu" "B.Mask" "B.Paste")
			(roundrect_rratio 0.25)
			(net 1300 "Net-(Q34-D)")
			(pintype "passive")
		)
		(pad "2" smd roundrect
			(at 0.48 0)
			(size 0.59 0.64)
			(layers "B.Cu" "B.Mask" "B.Paste")
			(roundrect_rratio 0.25)
			(net 11 "+1V8")
			(pintype "passive")
		)
	)
	(footprint "antmicro-footprints:R_0402_1005Metric"
		(layer "B.Cu")
		(at 220.66 114.01)
		(descr "Resistor SMD 0402")
		(tags "resistor SMD 0402")
		(property "Reference" "R330"
			(at -1.06 1.77 0)
			(layer "B.SilkS")
			(effects
				(font
					(size 0.7 0.7)
					(thickness 0.15)
				)
				(justify right top mirror)
			)
		)
		(property "Value" "R_2R2_0402"
			(at -1.011843 -1.772047 0)
			(layer "B.Fab")
			(effects
				(font
					(size 0.7 0.7)
					(thickness 0.15)
				)
				(justify right top mirror)
			)
		)
		(property "Datasheet" "https://www.bourns.com/docs/product-datasheets/cr.pdf"
			(at 0 0 0)
			(layer "B.Fab")
			(hide yes)
			(effects
				(font
					(size 1.27 1.27)
					(thickness 0.15)
				)
				(justify mirror)
			)
		)
		(property "Description" "SMD Chip Resistor, 2.2 ohm, ± 1%, 62.5 mW, 0402 [1005 Metric], Thick Film, General Purpose"
			(at 0 0 0)
			(layer "B.Fab")
			(hide yes)
			(effects
				(font
					(size 1.27 1.27)
					(thickness 0.15)
				)
				(justify mirror)
			)
		)
		(property "MPN" "CR0402-FX-2R20GLF"
			(at 0 0 180)
			(unlocked yes)
			(layer "B.Fab")
			(hide yes)
			(effects
				(font
					(size 1 1)
					(thickness 0.15)
				)
				(justify mirror)
			)
		)
		(property "Manufacturer" "Bourns"
			(at 0 0 180)
			(unlocked yes)
			(layer "B.Fab")
			(hide yes)
			(effects
				(font
					(size 1 1)
					(thickness 0.15)
				)
				(justify mirror)
			)
		)
		(property "License" "Apache-2.0"
			(at 0 0 180)
			(unlocked yes)
			(layer "B.Fab")
			(hide yes)
			(effects
				(font
					(size 1 1)
					(thickness 0.15)
				)
				(justify mirror)
			)
		)
		(property "Author" "Antmicro"
			(at 0 0 180)
			(unlocked yes)
			(layer "B.Fab")
			(hide yes)
			(effects
				(font
					(size 1 1)
					(thickness 0.15)
				)
				(justify mirror)
			)
		)
		(property "Val" "2R2"
			(at 0 0 180)
			(unlocked yes)
			(layer "B.Fab")
			(hide yes)
			(effects
				(font
					(size 1 1)
					(thickness 0.15)
				)
				(justify mirror)
			)
		)
		(property "Tolerance" "1%"
			(at 0 0 180)
			(unlocked yes)
			(layer "B.Fab")
			(hide yes)
			(effects
				(font
					(size 1 1)
					(thickness 0.15)
				)
				(justify mirror)
			)
		)
		(sheetname "/USB Hub/")
		(sheetfile "usb_hub.kicad_sch")
		(attr smd)
		(fp_rect
			(start -0.925 0.47)
			(end 0.925 -0.47)
			(stroke
				(width 0.05)
				(type default)
			)
			(fill no)
			(layer "B.CrtYd")
		)
		(fp_rect
			(start -0.5 0.25)
			(end 0.5 -0.25)
			(stroke
				(width 0.15)
				(type solid)
			)
			(fill no)
			(layer "B.Fab")
		)
		(fp_text user "License: Apache-2.0"
			(at -0.95 -5.169 0)
			(layer "B.Fab")
			(effects
				(font
					(size 0.7 0.7)
					(thickness 0.15)
				)
				(justify right top mirror)
			)
		)
		(fp_text user "${REFERENCE}"
			(at -0.95 -3.168 0)
			(layer "B.Fab")
			(effects
				(font
					(size 0.7 0.7)
					(thickness 0.15)
				)
				(justify right top mirror)
			)
		)
		(fp_text user "Author: Antmicro"
			(at -0.95 -4.169 0)
			(layer "B.Fab")
			(effects
				(font
					(size 0.7 0.7)
					(thickness 0.15)
				)
				(justify right top mirror)
			)
		)
		(pad "1" smd roundrect
			(at -0.48 0)
			(size 0.59 0.64)
			(layers "B.Cu" "B.Mask" "B.Paste")
			(roundrect_rratio 0.25)
			(net 633 "Net-(D57-C)")
			(pintype "passive")
		)
		(pad "2" smd roundrect
			(at 0.48 0)
			(size 0.59 0.64)
			(layers "B.Cu" "B.Mask" "B.Paste")
			(roundrect_rratio 0.25)
			(net 510 "/USB Hub/USBC3_CC_{1}")
			(pintype "passive")
		)
	)
)
